(kicad_pcb
	(version 20260206)
	(generator "pcbnew")
	(generator_version "10.0")
	(general
		(thickness 1.6)
		(legacy_teardrops no)
	)
	(paper "A4")
	(title_block
		(title "Wiwynn_Tioga_Pass_MB.brd")
		(comment 1 "Tioga Pass / footprints 2545-2551 of 4770")
	)
	(layers
		(0 "F.Cu" signal "TOP")
		(4 "In1.Cu" signal "L2GND")
		(6 "In2.Cu" signal "L3")
		(8 "In3.Cu" signal "L4GND")
		(10 "In4.Cu" signal "L5")
		(12 "In5.Cu" signal "L6GND")
		(14 "In6.Cu" signal "L7VCC")
		(16 "In7.Cu" signal "L8VCC")
		(18 "In8.Cu" signal "L9GND")
		(20 "In9.Cu" signal "L10")
		(22 "In10.Cu" signal "L11GND")
		(24 "In11.Cu" signal "L12")
		(26 "In12.Cu" signal "L13GND")
		(2 "B.Cu" signal "BOTTOM")
		(9 "F.Adhes" user "F.Adhesive")
		(11 "B.Adhes" user "B.Adhesive")
		(13 "F.Paste" user "Package Geometry/Pastemask Top")
		(15 "B.Paste" user "Package Geometry/Pastemask Bottom")
		(5 "F.SilkS" user "Ref Des/Silkscreen Top")
		(7 "B.SilkS" user "Ref Des/Silkscreen Bottom")
		(1 "F.Mask" user "Board Geometry/Soldermask Top")
		(3 "B.Mask" user "Board Geometry/Soldermask Bottom")
		(17 "Dwgs.User" user "User.Drawings")
		(19 "Cmts.User" user "User.Comments")
		(21 "Eco1.User" user "User.Eco1")
		(23 "Eco2.User" user "User.Eco2")
		(25 "Edge.Cuts" user "Board Geometry/Outline")
		(27 "Margin" user)
		(31 "F.CrtYd" user "Package Geometry/Place Bound Top")
		(29 "B.CrtYd" user "Package Geometry/Place Bound Bottom")
		(35 "F.Fab" user "Ref Des/Assembly Top")
		(33 "B.Fab" user "Ref Des/Assembly Bottom")
	)
	(footprint ""
		(layer "B.Cu")
		(at 488.3531 -41.4274 -90)
		(property "Reference" "R1R12"
			(at 0 0 90)
			(layer "B.SilkS")
			(hide yes)
			(effects
				(font
					(size 1.27 1.27)
				)
				(justify mirror)
			)
		)
		(property "Value" ""
			(at 0 0 90)
			(layer "B.Fab")
			(effects
				(font
					(size 1.27 1.27)
				)
				(justify mirror)
			)
		)
		(duplicate_pad_numbers_are_jumpers no)
		(fp_poly
			(pts
				(xy 0.2794 -0.1016) (xy -0.2794 -0.1016) (xy -0.2794 0.9906) (xy 0.2794 0.9906)
			)
			(stroke
				(width 0)
				(type default)
			)
			(fill no)
			(layer "B.CrtYd")
		)
		(fp_line
			(start -0.2794 0.9906)
			(end -0.2794 -0.1016)
			(stroke
				(width 0.1)
				(type default)
			)
			(layer "B.Fab")
		)
		(fp_line
			(start 0.2794 0.9906)
			(end -0.2794 0.9906)
			(stroke
				(width 0.1)
				(type default)
			)
			(layer "B.Fab")
		)
		(fp_line
			(start -0.2794 -0.1016)
			(end 0.2794 -0.1016)
			(stroke
				(width 0.1)
				(type default)
			)
			(layer "B.Fab")
		)
		(fp_line
			(start 0.2794 -0.1016)
			(end 0.2794 0.9906)
			(stroke
				(width 0.1)
				(type default)
			)
			(layer "B.Fab")
		)
		(pad "1" smd rect
			(at 0 0 90)
			(size 0.508 0.508)
			(layers "B.Cu" "B.Mask" "B.Paste")
			(net "CLK_50M_CKMNG_SPRVLLE")
		)
		(pad "2" smd rect
			(at 0 0.889 90)
			(size 0.508 0.508)
			(layers "B.Cu" "B.Mask" "B.Paste")
			(net "GND")
		)
		(zone
			(layer "B.Cu")
			(hatch none 0.5)
			(connect_pads
				(clearance 0)
			)
			(min_thickness 0.25)
			(keepout
				(tracks not_allowed)
				(vias allowed)
				(pads allowed)
				(copperpour not_allowed)
				(footprints allowed)
			)
			(placement
				(enabled no)
				(sheetname "")
			)
			(fill
				(thermal_gap 0.5)
				(thermal_bridge_width 0.5)
				(island_removal_mode 0)
			)
			(polygon
				(pts
					(xy 487.7181 -41.1734) (xy 487.7181 -41.6814) (xy 488.0991 -41.6814) (xy 488.0991 -41.1734)
				)
			)
		)
		(zone
			(layer "B.Cu")
			(hatch none 0.5)
			(connect_pads
				(clearance 0)
			)
			(min_thickness 0.25)
			(keepout
				(tracks allowed)
				(vias not_allowed)
				(pads allowed)
				(copperpour not_allowed)
				(footprints allowed)
			)
			(placement
				(enabled no)
				(sheetname "")
			)
			(fill
				(thermal_gap 0.5)
				(thermal_bridge_width 0.5)
				(island_removal_mode 0)
			)
			(polygon
				(pts
					(xy 488.0991 -41.1734) (xy 488.0991 -41.6814) (xy 487.7181 -41.6814) (xy 487.7181 -41.1734)
				)
			)
		)
	)
	(footprint ""
		(layer "B.Cu")
		(at 375.3612 -156.337 -90)
		(property "Reference" "R3L15"
			(at 0 0 90)
			(layer "B.SilkS")
			(hide yes)
			(effects
				(font
					(size 1.27 1.27)
				)
				(justify mirror)
			)
		)
		(property "Value" ""
			(at 0 0 90)
			(layer "B.Fab")
			(effects
				(font
					(size 1.27 1.27)
				)
				(justify mirror)
			)
		)
		(duplicate_pad_numbers_are_jumpers no)
		(fp_poly
			(pts
				(xy 0.2794 -0.1016) (xy -0.2794 -0.1016) (xy -0.2794 0.9906) (xy 0.2794 0.9906)
			)
			(stroke
				(width 0)
				(type default)
			)
			(fill no)
			(layer "B.CrtYd")
		)
		(fp_line
			(start -0.2794 0.9906)
			(end -0.2794 -0.1016)
			(stroke
				(width 0.1)
				(type default)
			)
			(layer "B.Fab")
		)
		(fp_line
			(start 0.2794 0.9906)
			(end -0.2794 0.9906)
			(stroke
				(width 0.1)
				(type default)
			)
			(layer "B.Fab")
		)
		(fp_line
			(start -0.2794 -0.1016)
			(end 0.2794 -0.1016)
			(stroke
				(width 0.1)
				(type default)
			)
			(layer "B.Fab")
		)
		(fp_line
			(start 0.2794 -0.1016)
			(end 0.2794 0.9906)
			(stroke
				(width 0.1)
				(type default)
			)
			(layer "B.Fab")
		)
		(pad "1" smd rect
			(at 0 0 90)
			(size 0.508 0.508)
			(layers "B.Cu" "B.Mask" "B.Paste")
			(net "VR_PVNN_PCH_STBY_OCSET")
		)
		(pad "2" smd rect
			(at 0 0.889 90)
			(size 0.508 0.508)
			(layers "B.Cu" "B.Mask" "B.Paste")
			(net "GND")
		)
		(zone
			(layer "B.Cu")
			(hatch none 0.5)
			(connect_pads
				(clearance 0)
			)
			(min_thickness 0.25)
			(keepout
				(tracks not_allowed)
				(vias allowed)
				(pads allowed)
				(copperpour not_allowed)
				(footprints allowed)
			)
			(placement
				(enabled no)
				(sheetname "")
			)
			(fill
				(thermal_gap 0.5)
				(thermal_bridge_width 0.5)
				(island_removal_mode 0)
			)
			(polygon
				(pts
					(xy 374.7262 -156.083) (xy 374.7262 -156.591) (xy 375.1072 -156.591) (xy 375.1072 -156.083)
				)
			)
		)
		(zone
			(layer "B.Cu")
			(hatch none 0.5)
			(connect_pads
				(clearance 0)
			)
			(min_thickness 0.25)
			(keepout
				(tracks allowed)
				(vias not_allowed)
				(pads allowed)
				(copperpour not_allowed)
				(footprints allowed)
			)
			(placement
				(enabled no)
				(sheetname "")
			)
			(fill
				(thermal_gap 0.5)
				(thermal_bridge_width 0.5)
				(island_removal_mode 0)
			)
			(polygon
				(pts
					(xy 375.1072 -156.083) (xy 375.1072 -156.591) (xy 374.7262 -156.591) (xy 374.7262 -156.083)
				)
			)
		)
	)
	(footprint ""
		(layer "B.Cu")
		(at 259.6642 -17.5514 90)
		(property "Reference" "C5U1"
			(at 0 0 90)
			(layer "B.SilkS")
			(hide yes)
			(effects
				(font
					(size 1.27 1.27)
				)
				(justify mirror)
			)
		)
		(property "Value" ""
			(at 0 0 90)
			(layer "B.Fab")
			(effects
				(font
					(size 1.27 1.27)
				)
				(justify mirror)
			)
		)
		(duplicate_pad_numbers_are_jumpers no)
		(fp_rect
			(start -0.7239 -0.2159)
			(end 0.7239 1.9939)
			(stroke
				(width 0)
				(type default)
			)
			(fill no)
			(layer "B.CrtYd")
		)
		(fp_line
			(start 0.7239 -0.2159)
			(end 0.7239 1.9939)
			(stroke
				(width 0.1)
				(type default)
			)
			(layer "B.Fab")
		)
		(fp_line
			(start -0.7239 -0.2159)
			(end 0.7239 -0.2159)
			(stroke
				(width 0.1)
				(type default)
			)
			(layer "B.Fab")
		)
		(fp_line
			(start 0.7239 1.9939)
			(end -0.7239 1.9939)
			(stroke
				(width 0.1)
				(type default)
			)
			(layer "B.Fab")
		)
		(fp_line
			(start -0.7239 1.9939)
			(end -0.7239 -0.2159)
			(stroke
				(width 0.1)
				(type default)
			)
			(layer "B.Fab")
		)
		(pad "1" smd rect
			(at 0 0 270)
			(size 1.27 1.016)
			(layers "B.Cu" "B.Mask" "B.Paste")
			(net "PVDDQ_ABC")
		)
		(pad "2" smd rect
			(at 0 1.778 270)
			(size 1.27 1.016)
			(layers "B.Cu" "B.Mask" "B.Paste")
			(net "GND")
		)
		(zone
			(layer "B.Cu")
			(hatch none 0.5)
			(connect_pads
				(clearance 0)
			)
			(min_thickness 0.25)
			(keepout
				(tracks not_allowed)
				(vias allowed)
				(pads allowed)
				(copperpour not_allowed)
				(footprints allowed)
			)
			(placement
				(enabled no)
				(sheetname "")
			)
			(fill
				(thermal_gap 0.5)
				(thermal_bridge_width 0.5)
				(island_removal_mode 0)
			)
			(polygon
				(pts
					(xy 260.1722 -16.9164) (xy 260.9342 -16.9164) (xy 260.9342 -18.1864) (xy 260.1722 -18.1864)
				)
			)
		)
	)
	(footprint ""
		(layer "B.Cu")
		(at 387.73735 -111.05515 180)
		(property "Reference" "C3N4"
			(at 0 0 0)
			(layer "B.SilkS")
			(hide yes)
			(effects
				(font
					(size 1.27 1.27)
				)
				(justify mirror)
			)
		)
		(property "Value" ""
			(at 0 0 0)
			(layer "B.Fab")
			(effects
				(font
					(size 1.27 1.27)
				)
				(justify mirror)
			)
		)
		(duplicate_pad_numbers_are_jumpers no)
		(fp_rect
			(start 0.2794 0.9144)
			(end -0.2794 -0.1143)
			(stroke
				(width 0)
				(type default)
			)
			(fill no)
			(layer "B.CrtYd")
		)
		(fp_line
			(start 0.2794 0.9144)
			(end 0.2794 -0.1143)
			(stroke
				(width 0.1)
				(type default)
			)
			(layer "B.Fab")
		)
		(fp_line
			(start 0.2794 -0.1143)
			(end -0.2794 -0.1143)
			(stroke
				(width 0.1)
				(type default)
			)
			(layer "B.Fab")
		)
		(fp_line
			(start -0.2794 0.9144)
			(end 0.2794 0.9144)
			(stroke
				(width 0.1)
				(type default)
			)
			(layer "B.Fab")
		)
		(fp_line
			(start -0.2794 -0.1143)
			(end -0.2794 0.9144)
			(stroke
				(width 0.1)
				(type default)
			)
			(layer "B.Fab")
		)
		(pad "1" smd custom
			(at 0 0 90)
			(size 0.10414 0.10414)
			(layers "B.Cu" "B.Mask" "B.Paste")
			(net "PVNN_PCH_STBY")
			(options
				(clearance outline)
				(anchor circle)
			)
			(primitives
				(gr_poly
					(pts
						(xy -0.20828 -0.08636) (xy -0.20828 0.08636) (xy -0.08636 0.20828) (xy 0.086614 0.20828) (xy 0.20828 0.086614)
						(xy 0.20828 -0.08636) (xy 0.08636 -0.20828) (xy -0.08636 -0.20828)
					)
					(width 0)
					(fill yes)
				)
			)
		)
		(pad "2" smd custom
			(at 0 0.8001 90)
			(size 0.10414 0.10414)
			(layers "B.Cu" "B.Mask" "B.Paste")
			(net "GND")
			(options
				(clearance outline)
				(anchor circle)
			)
			(primitives
				(gr_poly
					(pts
						(xy -0.20828 -0.08636) (xy -0.20828 0.08636) (xy -0.08636 0.20828) (xy 0.086614 0.20828) (xy 0.20828 0.086614)
						(xy 0.20828 -0.08636) (xy 0.08636 -0.20828) (xy -0.08636 -0.20828)
					)
					(width 0)
					(fill yes)
				)
			)
		)
		(zone
			(layer "B.Cu")
			(hatch none 0.5)
			(connect_pads
				(clearance 0)
			)
			(min_thickness 0.25)
			(keepout
				(tracks allowed)
				(vias not_allowed)
				(pads allowed)
				(copperpour not_allowed)
				(footprints allowed)
			)
			(placement
				(enabled no)
				(sheetname "")
			)
			(fill
				(thermal_gap 0.5)
				(thermal_bridge_width 0.5)
				(island_removal_mode 0)
			)
			(polygon
				(pts
					(xy 387.64972 -111.2647) (xy 387.64972 -111.6457) (xy 387.82498 -111.6457) (xy 387.825234 -111.2647)
				)
			)
		)
		(zone
			(layer "B.Cu")
			(hatch none 0.5)
			(connect_pads
				(clearance 0)
			)
			(min_thickness 0.25)
			(keepout
				(tracks not_allowed)
				(vias allowed)
				(pads allowed)
				(copperpour not_allowed)
				(footprints allowed)
			)
			(placement
				(enabled no)
				(sheetname "")
			)
			(fill
				(thermal_gap 0.5)
				(thermal_bridge_width 0.5)
				(island_removal_mode 0)
			)
			(polygon
				(pts
					(xy 387.64972 -111.2647) (xy 387.64972 -111.6457) (xy 387.82498 -111.6457) (xy 387.825234 -111.2647)
				)
			)
		)
	)
	(footprint ""
		(layer "B.Cu")
		(at 80.153002 -87.632286 -90)
		(property "Reference" "R8P1"
			(at 0 0 90)
			(layer "B.SilkS")
			(hide yes)
			(effects
				(font
					(size 1.27 1.27)
				)
				(justify mirror)
			)
		)
		(property "Value" ""
			(at 0 0 90)
			(layer "B.Fab")
			(effects
				(font
					(size 1.27 1.27)
				)
				(justify mirror)
			)
		)
		(duplicate_pad_numbers_are_jumpers no)
		(fp_poly
			(pts
				(xy 0.2794 -0.1016) (xy -0.2794 -0.1016) (xy -0.2794 0.9906) (xy 0.2794 0.9906)
			)
			(stroke
				(width 0)
				(type default)
			)
			(fill no)
			(layer "B.CrtYd")
		)
		(fp_line
			(start -0.2794 0.9906)
			(end -0.2794 -0.1016)
			(stroke
				(width 0.1)
				(type default)
			)
			(layer "B.Fab")
		)
		(fp_line
			(start 0.2794 0.9906)
			(end -0.2794 0.9906)
			(stroke
				(width 0.1)
				(type default)
			)
			(layer "B.Fab")
		)
		(fp_line
			(start -0.2794 -0.1016)
			(end 0.2794 -0.1016)
			(stroke
				(width 0.1)
				(type default)
			)
			(layer "B.Fab")
		)
		(fp_line
			(start 0.2794 -0.1016)
			(end 0.2794 0.9906)
			(stroke
				(width 0.1)
				(type default)
			)
			(layer "B.Fab")
		)
		(pad "1" smd rect
			(at 0 0 90)
			(size 0.508 0.508)
			(layers "B.Cu" "B.Mask" "B.Paste")
			(net "PD_CPU1_TEST14")
		)
		(pad "2" smd rect
			(at 0 0.889 90)
			(size 0.508 0.508)
			(layers "B.Cu" "B.Mask" "B.Paste")
			(net "GND")
		)
		(zone
			(layer "B.Cu")
			(hatch none 0.5)
			(connect_pads
				(clearance 0)
			)
			(min_thickness 0.25)
			(keepout
				(tracks not_allowed)
				(vias allowed)
				(pads allowed)
				(copperpour not_allowed)
				(footprints allowed)
			)
			(placement
				(enabled no)
				(sheetname "")
			)
			(fill
				(thermal_gap 0.5)
				(thermal_bridge_width 0.5)
				(island_removal_mode 0)
			)
			(polygon
				(pts
					(xy 79.518002 -87.378286) (xy 79.518002 -87.886286) (xy 79.899002 -87.886286) (xy 79.899002 -87.378286)
				)
			)
		)
		(zone
			(layer "B.Cu")
			(hatch none 0.5)
			(connect_pads
				(clearance 0)
			)
			(min_thickness 0.25)
			(keepout
				(tracks allowed)
				(vias not_allowed)
				(pads allowed)
				(copperpour not_allowed)
				(footprints allowed)
			)
			(placement
				(enabled no)
				(sheetname "")
			)
			(fill
				(thermal_gap 0.5)
				(thermal_bridge_width 0.5)
				(island_removal_mode 0)
			)
			(polygon
				(pts
					(xy 79.899002 -87.378286) (xy 79.899002 -87.886286) (xy 79.518002 -87.886286) (xy 79.518002 -87.378286)
				)
			)
		)
	)
	(footprint ""
		(layer "B.Cu")
		(at 229.3747 -64.6303 180)
		(property "Reference" "R4E18"
			(at 0 0 0)
			(layer "B.SilkS")
			(hide yes)
			(effects
				(font
					(size 1.27 1.27)
				)
				(justify mirror)
			)
		)
		(property "Value" ""
			(at 0 0 0)
			(layer "B.Fab")
			(effects
				(font
					(size 1.27 1.27)
				)
				(justify mirror)
			)
		)
		(duplicate_pad_numbers_are_jumpers no)
		(fp_poly
			(pts
				(xy 0.2794 -0.1016) (xy -0.2794 -0.1016) (xy -0.2794 0.9906) (xy 0.2794 0.9906)
			)
			(stroke
				(width 0)
				(type default)
			)
			(fill no)
			(layer "B.CrtYd")
		)
		(fp_line
			(start 0.2794 0.9906)
			(end -0.2794 0.9906)
			(stroke
				(width 0.1)
				(type default)
			)
			(layer "B.Fab")
		)
		(fp_line
			(start 0.2794 -0.1016)
			(end 0.2794 0.9906)
			(stroke
				(width 0.1)
				(type default)
			)
			(layer "B.Fab")
		)
		(fp_line
			(start -0.2794 0.9906)
			(end -0.2794 -0.1016)
			(stroke
				(width 0.1)
				(type default)
			)
			(layer "B.Fab")
		)
		(fp_line
			(start -0.2794 -0.1016)
			(end 0.2794 -0.1016)
			(stroke
				(width 0.1)
				(type default)
			)
			(layer "B.Fab")
		)
		(pad "1" smd rect
			(at 0 0)
			(size 0.508 0.508)
			(layers "B.Cu" "B.Mask" "B.Paste")
			(net "VSENSE_PVCCIN_CPU0_N")
		)
		(pad "2" smd rect
			(at 0 0.889)
			(size 0.508 0.508)
			(layers "B.Cu" "B.Mask" "B.Paste")
			(net "GND")
		)
		(zone
			(layer "B.Cu")
			(hatch none 0.5)
			(connect_pads
				(clearance 0)
			)
			(min_thickness 0.25)
			(keepout
				(tracks not_allowed)
				(vias allowed)
				(pads allowed)
				(copperpour not_allowed)
				(footprints allowed)
			)
			(placement
				(enabled no)
				(sheetname "")
			)
			(fill
				(thermal_gap 0.5)
				(thermal_bridge_width 0.5)
				(island_removal_mode 0)
			)
			(polygon
				(pts
					(xy 229.1207 -65.2653) (xy 229.6287 -65.2653) (xy 229.6287 -64.8843) (xy 229.1207 -64.8843)
				)
			)
		)
		(zone
			(layer "B.Cu")
			(hatch none 0.5)
			(connect_pads
				(clearance 0)
			)
			(min_thickness 0.25)
			(keepout
				(tracks allowed)
				(vias not_allowed)
				(pads allowed)
				(copperpour not_allowed)
				(footprints allowed)
			)
			(placement
				(enabled no)
				(sheetname "")
			)
			(fill
				(thermal_gap 0.5)
				(thermal_bridge_width 0.5)
				(island_removal_mode 0)
			)
			(polygon
				(pts
					(xy 229.1207 -64.8843) (xy 229.6287 -64.8843) (xy 229.6287 -65.2653) (xy 229.1207 -65.2653)
				)
			)
		)
	)
	(footprint ""
		(layer "B.Cu")
		(at 80.731868 -149.8092 -90)
		(property "Reference" "C5G101"
			(at -1.14681 0.76708 0)
			(unlocked yes)
			(layer "B.SilkS")
			(effects
				(font
					(size 0.7874 0.5842)
					(thickness 0.1524)
				)
				(justify mirror)
			)
		)
		(property "Value" ""
			(at 0 0 90)
			(layer "B.Fab")
			(effects
				(font
					(size 1.27 1.27)
				)
				(justify mirror)
			)
		)
		(duplicate_pad_numbers_are_jumpers no)
		(fp_rect
			(start 0.4953 1.6002)
			(end -0.4953 -0.2032)
			(stroke
				(width 0)
				(type default)
			)
			(fill no)
			(layer "B.CrtYd")
		)
		(fp_line
			(start -0.4953 1.6002)
			(end 0.4953 1.6002)
			(stroke
				(width 0.1)
				(type default)
			)
			(layer "B.Fab")
		)
		(fp_line
			(start 0.4953 1.6002)
			(end 0.4953 -0.2032)
			(stroke
				(width 0.1)
				(type default)
			)
			(layer "B.Fab")
		)
		(fp_line
			(start -0.4953 -0.2032)
			(end -0.4953 1.6002)
			(stroke
				(width 0.1)
				(type default)
			)
			(layer "B.Fab")
		)
		(fp_line
			(start 0.4953 -0.2032)
			(end -0.4953 -0.2032)
			(stroke
				(width 0.1)
				(type default)
			)
			(layer "B.Fab")
		)
		(pad "1" smd rect
			(at 0 0 90)
			(size 0.762 0.889)
			(layers "B.Cu" "B.Mask" "B.Paste")
			(net "PVDDQ_KLM")
		)
		(pad "2" smd rect
			(at 0 1.397 90)
			(size 0.762 0.889)
			(layers "B.Cu" "B.Mask" "B.Paste")
			(net "GND")
		)
		(zone
			(layer "B.Cu")
			(hatch none 0.5)
			(connect_pads
				(clearance 0)
			)
			(min_thickness 0.25)
			(keepout
				(tracks not_allowed)
				(vias allowed)
				(pads allowed)
				(copperpour not_allowed)
				(footprints allowed)
			)
			(placement
				(enabled no)
				(sheetname "")
			)
			(fill
				(thermal_gap 0.5)
				(thermal_bridge_width 0.5)
				(island_removal_mode 0)
			)
			(polygon
				(pts
					(xy 79.779368 -149.4282) (xy 80.287368 -149.4282) (xy 80.287368 -150.1902) (xy 79.779368 -150.1902)
				)
			)
		)
	)
)
